(kicad_pcb
	(version 20260206)
	(generator "pcbnew")
	(generator_version "10.0")
	(general
		(thickness 1.6)
		(legacy_teardrops no)
	)
	(paper "A4")
	(title_block
		(title "Bryce Canyon_F.DPB_16315-1-OCP.brd")
		(comment 1 "Bryce Canyon / footprints 2040-2047 of 2223")
	)
	(layers
		(0 "F.Cu" signal "TOP")
		(4 "In1.Cu" signal "L2GND")
		(6 "In2.Cu" signal "L3")
		(8 "In3.Cu" signal "L4GND")
		(10 "In4.Cu" signal "L5")
		(12 "In5.Cu" signal "L6VCC")
		(14 "In6.Cu" signal "L7VCC")
		(16 "In7.Cu" signal "L8")
		(18 "In8.Cu" signal "L9GND")
		(20 "In9.Cu" signal "L10")
		(22 "In10.Cu" signal "L11GND")
		(2 "B.Cu" signal "BOTTOM")
		(9 "F.Adhes" user "F.Adhesive")
		(11 "B.Adhes" user "B.Adhesive")
		(13 "F.Paste" user "Package Geometry/Pastemask Top")
		(15 "B.Paste" user "Package Geometry/Pastemask Bottom")
		(5 "F.SilkS" user "Ref Des/Silkscreen Top")
		(7 "B.SilkS" user "Ref Des/Silkscreen Bottom")
		(1 "F.Mask" user "Board Geometry/Soldermask Top")
		(3 "B.Mask" user "Board Geometry/Soldermask Bottom")
		(17 "Dwgs.User" user "User.Drawings")
		(19 "Cmts.User" user "User.Comments")
		(21 "Eco1.User" user "User.Eco1")
		(23 "Eco2.User" user "User.Eco2")
		(25 "Edge.Cuts" user "Board Geometry/Outline")
		(27 "Margin" user)
		(31 "F.CrtYd" user "Package Geometry/Place Bound Top")
		(29 "B.CrtYd" user "Package Geometry/Place Bound Bottom")
		(35 "F.Fab" user "Ref Des/Assembly Top")
		(33 "B.Fab" user "Ref Des/Assembly Bottom")
	)
	(footprint ""
		(layer "B.Cu")
		(at 51.949604 -148.778214 -90)
		(property "Reference" "R1235"
			(at 0 0 90)
			(layer "B.SilkS")
			(hide yes)
			(effects
				(font
					(size 1.27 1.27)
				)
				(justify mirror)
			)
		)
		(property "Value" "10R3F-GP"
			(at 0.0254 -2.5146 270)
			(unlocked yes)
			(layer "B.Fab")
			(hide yes)
			(effects
				(font
					(size 1.016 1.016)
					(thickness 0.1524)
				)
				(justify mirror)
			)
		)
		(property "Device Type" "R603H22"
			(at 0.0254 -4.0386 270)
			(unlocked yes)
			(layer "B.Fab")
			(hide yes)
			(effects
				(font
					(size 1.016 1.016)
					(thickness 0.1524)
				)
				(justify mirror)
			)
		)
		(duplicate_pad_numbers_are_jumpers no)
		(fp_line
			(start -0.2032 0)
			(end -0.4826 0)
			(stroke
				(width 0.2032)
				(type default)
			)
			(layer "B.SilkS")
		)
		(fp_line
			(start 0.4826 0)
			(end 0.2032 0)
			(stroke
				(width 0.2032)
				(type default)
			)
			(layer "B.SilkS")
		)
		(fp_rect
			(start 0.5842 1.3335)
			(end -0.5842 -1.3335)
			(stroke
				(width 0)
				(type default)
			)
			(fill no)
			(layer "B.CrtYd")
		)
		(fp_rect
			(start 0.5842 1.3335)
			(end -0.5842 -1.3335)
			(stroke
				(width 0)
				(type default)
			)
			(fill no)
			(layer "B.Fab")
		)
		(pad "1" smd custom
			(at 0 -0.762 90)
			(size 0.2159 0.2159)
			(layers "B.Cu" "B.Mask" "B.Paste")
			(net "P5V_B_CC")
			(options
				(clearance outline)
				(anchor circle)
			)
			(primitives
				(gr_poly
					(pts
						(arc
							(start -0.3302 0.4318)
							(mid -0.402042 0.402042)
							(end -0.4318 0.3302)
						)
						(arc
							(start -0.4318 -0.3302)
							(mid -0.402042 -0.402042)
							(end -0.3302 -0.4318)
						)
						(arc
							(start 0.3302 -0.4318)
							(mid 0.402042 -0.402042)
							(end 0.4318 -0.3302)
						)
						(arc
							(start 0.4318 0.3302)
							(mid 0.402042 0.402042)
							(end 0.3302 0.4318)
						)
					)
					(width 0)
					(fill yes)
				)
			)
		)
		(pad "2" smd custom
			(at 0 0.762 90)
			(size 0.2159 0.2159)
			(layers "B.Cu" "B.Mask" "B.Paste")
			(net "P5V_B_VFB_R")
			(options
				(clearance outline)
				(anchor circle)
			)
			(primitives
				(gr_poly
					(pts
						(arc
							(start -0.3302 0.4318)
							(mid -0.402042 0.402042)
							(end -0.4318 0.3302)
						)
						(arc
							(start -0.4318 -0.3302)
							(mid -0.402042 -0.402042)
							(end -0.3302 -0.4318)
						)
						(arc
							(start 0.3302 -0.4318)
							(mid 0.402042 -0.402042)
							(end 0.4318 -0.3302)
						)
						(arc
							(start 0.4318 0.3302)
							(mid 0.402042 0.402042)
							(end 0.3302 0.4318)
						)
					)
					(width 0)
					(fill yes)
				)
			)
		)
	)
	(footprint ""
		(layer "B.Cu")
		(at 189.911482 -219.707206 -90)
		(property "Reference" "R1285"
			(at 0 0 90)
			(layer "B.SilkS")
			(hide yes)
			(effects
				(font
					(size 1.27 1.27)
				)
				(justify mirror)
			)
		)
		(property "Value" "33KR2J-3-GP"
			(at -0.064008 -3.993896 270)
			(unlocked yes)
			(layer "B.Fab")
			(hide yes)
			(effects
				(font
					(size 1.016 1.016)
					(thickness 0.1524)
				)
				(justify mirror)
			)
		)
		(property "Device Type" "R402H16"
			(at -0.064008 -5.517896 270)
			(unlocked yes)
			(layer "B.Fab")
			(hide yes)
			(effects
				(font
					(size 1.016 1.016)
					(thickness 0.1524)
				)
				(justify mirror)
			)
		)
		(duplicate_pad_numbers_are_jumpers no)
		(fp_line
			(start -0.508 -0.9398)
			(end 0.508 -0.9398)
			(stroke
				(width 0.1524)
				(type default)
			)
			(layer "B.SilkS")
		)
		(fp_line
			(start 0.508 -0.9398)
			(end 0.508 0.9398)
			(stroke
				(width 0.1524)
				(type default)
			)
			(layer "B.SilkS")
		)
		(fp_rect
			(start 0.508 0.9398)
			(end -0.508 -0.9398)
			(stroke
				(width 0)
				(type default)
			)
			(fill no)
			(layer "B.CrtYd")
		)
		(fp_rect
			(start 0.508 0.9398)
			(end -0.508 -0.9398)
			(stroke
				(width 0)
				(type default)
			)
			(fill no)
			(layer "B.Fab")
		)
		(pad "1" smd custom
			(at 0 -0.4445 90)
			(size 0.1397 0.1397)
			(layers "B.Cu" "B.Mask" "B.Paste")
			(net "P3V3_STBY_CC_R")
			(options
				(clearance outline)
				(anchor circle)
			)
			(primitives
				(gr_poly
					(pts
						(arc
							(start -0.1778 0.2794)
							(mid -0.249642 0.249642)
							(end -0.2794 0.1778)
						)
						(arc
							(start -0.2794 -0.1778)
							(mid -0.249642 -0.249642)
							(end -0.1778 -0.2794)
						)
						(arc
							(start 0.1778 -0.2794)
							(mid 0.249642 -0.249642)
							(end 0.2794 -0.1778)
						)
						(arc
							(start 0.2794 0.1778)
							(mid 0.249642 0.249642)
							(end 0.1778 0.2794)
						)
					)
					(width 0)
					(fill yes)
				)
			)
		)
		(pad "2" smd custom
			(at 0 0.4445 90)
			(size 0.1397 0.1397)
			(layers "B.Cu" "B.Mask" "B.Paste")
			(net "P3V3_STBY_VFB")
			(options
				(clearance outline)
				(anchor circle)
			)
			(primitives
				(gr_poly
					(pts
						(arc
							(start -0.1778 0.2794)
							(mid -0.249642 0.249642)
							(end -0.2794 0.1778)
						)
						(arc
							(start -0.2794 -0.1778)
							(mid -0.249642 -0.249642)
							(end -0.1778 -0.2794)
						)
						(arc
							(start 0.1778 -0.2794)
							(mid 0.249642 -0.249642)
							(end 0.2794 -0.1778)
						)
						(arc
							(start 0.2794 0.1778)
							(mid 0.249642 0.249642)
							(end 0.1778 0.2794)
						)
					)
					(width 0)
					(fill yes)
				)
			)
		)
	)
	(footprint ""
		(layer "B.Cu")
		(at 449.3514 -256.4638 90)
		(property "Reference" "R1256"
			(at 0 0 90)
			(layer "B.SilkS")
			(hide yes)
			(effects
				(font
					(size 1.27 1.27)
				)
				(justify mirror)
			)
		)
		(property "Value" "71K5R2F-GP"
			(at -0.064008 -3.993896 90)
			(unlocked yes)
			(layer "B.Fab")
			(hide yes)
			(effects
				(font
					(size 1.016 1.016)
					(thickness 0.1524)
				)
				(justify mirror)
			)
		)
		(property "Device Type" "R402H16"
			(at -0.064008 -5.517896 90)
			(unlocked yes)
			(layer "B.Fab")
			(hide yes)
			(effects
				(font
					(size 1.016 1.016)
					(thickness 0.1524)
				)
				(justify mirror)
			)
		)
		(duplicate_pad_numbers_are_jumpers no)
		(fp_line
			(start 0.508 -0.9398)
			(end 0.508 0.9398)
			(stroke
				(width 0.1524)
				(type default)
			)
			(layer "B.SilkS")
		)
		(fp_line
			(start -0.508 -0.9398)
			(end 0.508 -0.9398)
			(stroke
				(width 0.1524)
				(type default)
			)
			(layer "B.SilkS")
		)
		(fp_rect
			(start 0.508 0.9398)
			(end -0.508 -0.9398)
			(stroke
				(width 0)
				(type default)
			)
			(fill no)
			(layer "B.CrtYd")
		)
		(fp_rect
			(start 0.508 0.9398)
			(end -0.508 -0.9398)
			(stroke
				(width 0)
				(type default)
			)
			(fill no)
			(layer "B.Fab")
		)
		(pad "1" smd custom
			(at 0 -0.4445 270)
			(size 0.1397 0.1397)
			(layers "B.Cu" "B.Mask" "B.Paste")
			(net "P5V_C_VFB")
			(options
				(clearance outline)
				(anchor circle)
			)
			(primitives
				(gr_poly
					(pts
						(arc
							(start -0.1778 0.2794)
							(mid -0.249642 0.249642)
							(end -0.2794 0.1778)
						)
						(arc
							(start -0.2794 -0.1778)
							(mid -0.249642 -0.249642)
							(end -0.1778 -0.2794)
						)
						(arc
							(start 0.1778 -0.2794)
							(mid 0.249642 -0.249642)
							(end 0.2794 -0.1778)
						)
						(arc
							(start 0.2794 0.1778)
							(mid 0.249642 0.249642)
							(end 0.1778 0.2794)
						)
					)
					(width 0)
					(fill yes)
				)
			)
		)
		(pad "2" smd custom
			(at 0 0.4445 270)
			(size 0.1397 0.1397)
			(layers "B.Cu" "B.Mask" "B.Paste")
			(net "P5V_C_VFB_R")
			(options
				(clearance outline)
				(anchor circle)
			)
			(primitives
				(gr_poly
					(pts
						(arc
							(start -0.1778 0.2794)
							(mid -0.249642 0.249642)
							(end -0.2794 0.1778)
						)
						(arc
							(start -0.2794 -0.1778)
							(mid -0.249642 -0.249642)
							(end -0.1778 -0.2794)
						)
						(arc
							(start 0.1778 -0.2794)
							(mid 0.249642 -0.249642)
							(end 0.2794 -0.1778)
						)
						(arc
							(start 0.2794 0.1778)
							(mid 0.249642 0.249642)
							(end 0.1778 0.2794)
						)
					)
					(width 0)
					(fill yes)
				)
			)
		)
	)
	(footprint ""
		(layer "B.Cu")
		(at 483.859586 -230.0605 -90)
		(property "Reference" "R1273"
			(at 0 0 90)
			(layer "B.SilkS")
			(hide yes)
			(effects
				(font
					(size 1.27 1.27)
				)
				(justify mirror)
			)
		)
		(property "Value" "10R3F-GP"
			(at 0.0254 -2.5146 270)
			(unlocked yes)
			(layer "B.Fab")
			(hide yes)
			(effects
				(font
					(size 1.016 1.016)
					(thickness 0.1524)
				)
				(justify mirror)
			)
		)
		(property "Device Type" "R603H22"
			(at 0.0254 -4.0386 270)
			(unlocked yes)
			(layer "B.Fab")
			(hide yes)
			(effects
				(font
					(size 1.016 1.016)
					(thickness 0.1524)
				)
				(justify mirror)
			)
		)
		(duplicate_pad_numbers_are_jumpers no)
		(fp_line
			(start -0.2032 0)
			(end -0.4826 0)
			(stroke
				(width 0.2032)
				(type default)
			)
			(layer "B.SilkS")
		)
		(fp_line
			(start 0.4826 0)
			(end 0.2032 0)
			(stroke
				(width 0.2032)
				(type default)
			)
			(layer "B.SilkS")
		)
		(fp_rect
			(start 0.5842 1.3335)
			(end -0.5842 -1.3335)
			(stroke
				(width 0)
				(type default)
			)
			(fill no)
			(layer "B.CrtYd")
		)
		(fp_rect
			(start 0.5842 1.3335)
			(end -0.5842 -1.3335)
			(stroke
				(width 0)
				(type default)
			)
			(fill no)
			(layer "B.Fab")
		)
		(pad "1" smd custom
			(at 0 -0.762 90)
			(size 0.2159 0.2159)
			(layers "B.Cu" "B.Mask" "B.Paste")
			(net "P5V_D_CC")
			(options
				(clearance outline)
				(anchor circle)
			)
			(primitives
				(gr_poly
					(pts
						(arc
							(start -0.3302 0.4318)
							(mid -0.402042 0.402042)
							(end -0.4318 0.3302)
						)
						(arc
							(start -0.4318 -0.3302)
							(mid -0.402042 -0.402042)
							(end -0.3302 -0.4318)
						)
						(arc
							(start 0.3302 -0.4318)
							(mid 0.402042 -0.402042)
							(end 0.4318 -0.3302)
						)
						(arc
							(start 0.4318 0.3302)
							(mid 0.402042 0.402042)
							(end 0.3302 0.4318)
						)
					)
					(width 0)
					(fill yes)
				)
			)
		)
		(pad "2" smd custom
			(at 0 0.762 90)
			(size 0.2159 0.2159)
			(layers "B.Cu" "B.Mask" "B.Paste")
			(net "P5V_D_VFB_R")
			(options
				(clearance outline)
				(anchor circle)
			)
			(primitives
				(gr_poly
					(pts
						(arc
							(start -0.3302 0.4318)
							(mid -0.402042 0.402042)
							(end -0.4318 0.3302)
						)
						(arc
							(start -0.4318 -0.3302)
							(mid -0.402042 -0.402042)
							(end -0.3302 -0.4318)
						)
						(arc
							(start 0.3302 -0.4318)
							(mid 0.402042 -0.402042)
							(end 0.4318 -0.3302)
						)
						(arc
							(start 0.4318 0.3302)
							(mid 0.402042 0.402042)
							(end 0.3302 0.4318)
						)
					)
					(width 0)
					(fill yes)
				)
			)
		)
	)
	(footprint ""
		(layer "B.Cu")
		(at 482.219 -234.95 90)
		(property "Reference" "R1278"
			(at 0 0 90)
			(layer "B.SilkS")
			(hide yes)
			(effects
				(font
					(size 1.27 1.27)
				)
				(justify mirror)
			)
		)
		(property "Value" "619KR2F-GP"
			(at -0.064008 -3.993896 90)
			(unlocked yes)
			(layer "B.Fab")
			(hide yes)
			(effects
				(font
					(size 1.016 1.016)
					(thickness 0.1524)
				)
				(justify mirror)
			)
		)
		(property "Device Type" "R402H16"
			(at -0.064008 -5.517896 90)
			(unlocked yes)
			(layer "B.Fab")
			(hide yes)
			(effects
				(font
					(size 1.016 1.016)
					(thickness 0.1524)
				)
				(justify mirror)
			)
		)
		(duplicate_pad_numbers_are_jumpers no)
		(fp_line
			(start 0.508 -0.9398)
			(end 0.508 0.9398)
			(stroke
				(width 0.1524)
				(type default)
			)
			(layer "B.SilkS")
		)
		(fp_line
			(start -0.508 -0.9398)
			(end 0.508 -0.9398)
			(stroke
				(width 0.1524)
				(type default)
			)
			(layer "B.SilkS")
		)
		(fp_rect
			(start 0.508 0.9398)
			(end -0.508 -0.9398)
			(stroke
				(width 0)
				(type default)
			)
			(fill no)
			(layer "B.CrtYd")
		)
		(fp_rect
			(start 0.508 0.9398)
			(end -0.508 -0.9398)
			(stroke
				(width 0)
				(type default)
			)
			(fill no)
			(layer "B.Fab")
		)
		(pad "1" smd custom
			(at 0 -0.4445 270)
			(size 0.1397 0.1397)
			(layers "B.Cu" "B.Mask" "B.Paste")
			(net "P5V_D_RF")
			(options
				(clearance outline)
				(anchor circle)
			)
			(primitives
				(gr_poly
					(pts
						(arc
							(start -0.1778 0.2794)
							(mid -0.249642 0.249642)
							(end -0.2794 0.1778)
						)
						(arc
							(start -0.2794 -0.1778)
							(mid -0.249642 -0.249642)
							(end -0.1778 -0.2794)
						)
						(arc
							(start 0.1778 -0.2794)
							(mid 0.249642 -0.249642)
							(end 0.2794 -0.1778)
						)
						(arc
							(start 0.2794 0.1778)
							(mid 0.249642 0.249642)
							(end 0.1778 0.2794)
						)
					)
					(width 0)
					(fill yes)
				)
			)
		)
		(pad "2" smd custom
			(at 0 0.4445 270)
			(size 0.1397 0.1397)
			(layers "B.Cu" "B.Mask" "B.Paste")
			(net "AGND_P5V_D")
			(options
				(clearance outline)
				(anchor circle)
			)
			(primitives
				(gr_poly
					(pts
						(arc
							(start -0.1778 0.2794)
							(mid -0.249642 0.249642)
							(end -0.2794 0.1778)
						)
						(arc
							(start -0.2794 -0.1778)
							(mid -0.249642 -0.249642)
							(end -0.1778 -0.2794)
						)
						(arc
							(start 0.1778 -0.2794)
							(mid 0.249642 -0.249642)
							(end 0.2794 -0.1778)
						)
						(arc
							(start 0.2794 0.1778)
							(mid 0.249642 0.249642)
							(end 0.1778 0.2794)
						)
					)
					(width 0)
					(fill yes)
				)
			)
		)
	)
	(footprint ""
		(layer "B.Cu")
		(at 478.663 -230.505 180)
		(property "Reference" "R1280"
			(at 0 0 0)
			(layer "B.SilkS")
			(hide yes)
			(effects
				(font
					(size 1.27 1.27)
				)
				(justify mirror)
			)
		)
		(property "Value" "10KR2F-2-GP"
			(at -0.064008 -3.993896 180)
			(unlocked yes)
			(layer "B.Fab")
			(hide yes)
			(effects
				(font
					(size 1.016 1.016)
					(thickness 0.1524)
				)
				(justify mirror)
			)
		)
		(property "Device Type" "R402H16"
			(at -0.064008 -5.517896 180)
			(unlocked yes)
			(layer "B.Fab")
			(hide yes)
			(effects
				(font
					(size 1.016 1.016)
					(thickness 0.1524)
				)
				(justify mirror)
			)
		)
		(duplicate_pad_numbers_are_jumpers no)
		(fp_line
			(start 0.508 -0.9398)
			(end 0.508 0.9398)
			(stroke
				(width 0.1524)
				(type default)
			)
			(layer "B.SilkS")
		)
		(fp_line
			(start -0.508 -0.9398)
			(end 0.508 -0.9398)
			(stroke
				(width 0.1524)
				(type default)
			)
			(layer "B.SilkS")
		)
		(fp_rect
			(start 0.508 0.9398)
			(end -0.508 -0.9398)
			(stroke
				(width 0)
				(type default)
			)
			(fill no)
			(layer "B.CrtYd")
		)
		(fp_rect
			(start 0.508 0.9398)
			(end -0.508 -0.9398)
			(stroke
				(width 0)
				(type default)
			)
			(fill no)
			(layer "B.Fab")
		)
		(pad "1" smd custom
			(at 0 -0.4445)
			(size 0.1397 0.1397)
			(layers "B.Cu" "B.Mask" "B.Paste")
			(net "P5V_D_VFB")
			(options
				(clearance outline)
				(anchor circle)
			)
			(primitives
				(gr_poly
					(pts
						(arc
							(start -0.1778 0.2794)
							(mid -0.249642 0.249642)
							(end -0.2794 0.1778)
						)
						(arc
							(start -0.2794 -0.1778)
							(mid -0.249642 -0.249642)
							(end -0.1778 -0.2794)
						)
						(arc
							(start 0.1778 -0.2794)
							(mid 0.249642 -0.249642)
							(end 0.2794 -0.1778)
						)
						(arc
							(start 0.2794 0.1778)
							(mid 0.249642 0.249642)
							(end 0.1778 0.2794)
						)
					)
					(width 0)
					(fill yes)
				)
			)
		)
		(pad "2" smd custom
			(at 0 0.4445)
			(size 0.1397 0.1397)
			(layers "B.Cu" "B.Mask" "B.Paste")
			(net "AGND_P5V_D")
			(options
				(clearance outline)
				(anchor circle)
			)
			(primitives
				(gr_poly
					(pts
						(arc
							(start -0.1778 0.2794)
							(mid -0.249642 0.249642)
							(end -0.2794 0.1778)
						)
						(arc
							(start -0.2794 -0.1778)
							(mid -0.249642 -0.249642)
							(end -0.1778 -0.2794)
						)
						(arc
							(start 0.1778 -0.2794)
							(mid 0.249642 -0.249642)
							(end 0.2794 -0.1778)
						)
						(arc
							(start 0.2794 0.1778)
							(mid 0.249642 0.249642)
							(end 0.1778 0.2794)
						)
					)
					(width 0)
					(fill yes)
				)
			)
		)
	)
	(footprint ""
		(layer "B.Cu")
		(at 425.174918 -210.799934 180)
		(property "Reference" "SCW2"
			(at 0 0 0)
			(layer "B.SilkS")
			(hide yes)
			(effects
				(font
					(size 1.27 1.27)
				)
				(justify mirror)
			)
		)
		(property "Value" ""
			(at 0 0 0)
			(layer "B.Fab")
			(effects
				(font
					(size 1.27 1.27)
				)
				(justify mirror)
			)
		)
		(duplicate_pad_numbers_are_jumpers no)
		(fp_poly
			(pts
				(arc
					(start -5.4356 0)
					(mid 5.4356 0)
					(end -5.4356 0)
				)
			)
			(stroke
				(width 0)
				(type default)
			)
			(fill no)
			(layer "B.CrtYd")
		)
		(fp_poly
			(pts
				(arc
					(start -5.4356 0)
					(mid 5.4356 0)
					(end -5.4356 0)
				)
			)
			(stroke
				(width 0)
				(type default)
			)
			(fill no)
			(layer "F.CrtYd")
		)
		(fp_poly
			(pts
				(arc
					(start -5.4356 0)
					(mid 5.4356 0)
					(end -5.4356 0)
				)
			)
			(stroke
				(width 0)
				(type default)
			)
			(fill no)
			(layer "B.Fab")
		)
		(fp_poly
			(pts
				(arc
					(start -5.4356 0)
					(mid 5.4356 0)
					(end -5.4356 0)
				)
			)
			(stroke
				(width 0)
				(type default)
			)
			(fill no)
			(layer "F.Fab")
		)
		(pad "" np_thru_hole circle
			(at 0 0)
			(size 0.254 0.254)
			(drill 10.2616)
			(layers "*.Cu" "*.Mask")
			(clearance 5.3594)
			(thermal_gap 5.3594)
		)
		(zone
			(layers "F.Cu" "B.Cu" "In1.Cu" "In2.Cu" "In3.Cu" "In4.Cu" "In5.Cu" "In6.Cu"
				"In7.Cu" "In8.Cu" "In9.Cu" "In10.Cu"
			)
			(hatch none 0.5)
			(connect_pads
				(clearance 0)
			)
			(min_thickness 0.25)
			(keepout
				(tracks not_allowed)
				(vias allowed)
				(pads allowed)
				(copperpour not_allowed)
				(footprints allowed)
			)
			(placement
				(enabled no)
				(sheetname "")
			)
			(fill
				(thermal_gap 0.5)
				(thermal_bridge_width 0.5)
				(island_removal_mode 0)
			)
			(polygon
				(pts
					(arc
						(start 430.610518 -210.799934)
						(mid 419.739318 -210.799934)
						(end 430.610518 -210.799934)
					)
				)
			)
		)
	)
	(footprint ""
		(layer "B.Cu")
		(at 182.656226 -218.174062)
		(property "Reference" "TP260"
			(at 0 0 0)
			(layer "B.SilkS")
			(hide yes)
			(effects
				(font
					(size 1.27 1.27)
				)
				(justify mirror)
			)
		)
		(property "Value" "TPAD32-GP"
			(at 0.0508 -1.6764 0)
			(unlocked yes)
			(layer "B.Fab")
			(hide yes)
			(effects
				(font
					(size 1.016 1.016)
					(thickness 0.1524)
				)
				(justify mirror)
			)
		)
		(property "Device Type" "TPAD32"
			(at 0.0508 -3.2004 0)
			(unlocked yes)
			(layer "B.Fab")
			(hide yes)
			(effects
				(font
					(size 1.016 1.016)
					(thickness 0.1524)
				)
				(justify mirror)
			)
		)
		(duplicate_pad_numbers_are_jumpers no)
		(fp_poly
			(pts
				(arc
					(start 0.4064 0)
					(mid -0.4064 0)
					(end 0.4064 0)
				)
			)
			(stroke
				(width 0)
				(type default)
			)
			(fill no)
			(layer "B.CrtYd")
		)
		(fp_poly
			(pts
				(arc
					(start 0.7112 0)
					(mid -0.7112 0)
					(end 0.7112 0)
				)
			)
			(stroke
				(width 0)
				(type default)
			)
			(fill no)
			(layer "B.Fab")
		)
		(pad "1" smd circle
			(at 0 0 180)
			(size 0.8128 0.8128)
			(layers "B.Cu" "B.Mask" "B.Paste")
			(net "PWRGD_P3V3_STBY")
		)
	)
)
